# T6G (Grand Teton) — schematic netlist excerpt (pin names and nets, part order shuffled) for the footprints in the layout excerpt that follows; sources: Cadence DE-HDL packaged netlist, KiCad conversion of 04192023_DAF0TMB3IC0_F0TG_MB_C_brd_V02_OCP.brd

C625  Q_CAP  100UF 4V 20% X6S  pkg C0805  page 290 : A = P0V9_CPU0_RT1_2A ; B = GND
PC597  Q_CAPP  470UF 2.5V 20% EMPTY  pkg SMLF  page 198 : A = PVDDCR_SOC_P0 ; B = GND
C1004  Q_CAP  0.1UF 10V 10% X7S  pkg C0201  page 312 : A = P1V8_CPU0_RT3_1A ; B = GND

(kicad_pcb
	(version 20260206)
	(generator "pcbnew")
	(generator_version "10.0")
	(general
		(thickness 1.6)
		(legacy_teardrops no)
	)
	(paper "A4")
	(title_block
		(title "04192023_DAF0TMB3IC0_F0TG_MB_C_brd_V02_OCP.brd")
		(comment 1 "Grand Teton / footprints 6954-6956 of 8354")
	)
	(layers
		(0 "F.Cu" signal "TOP")
		(4 "In1.Cu" signal "GND")
		(6 "In2.Cu" signal "IN1")
		(8 "In3.Cu" signal "GND1")
		(10 "In4.Cu" signal "IN2")
		(12 "In5.Cu" signal "GND2")
		(14 "In6.Cu" signal "IN3")
		(16 "In7.Cu" signal "GND3")
		(18 "In8.Cu" signal "VCC")
		(20 "In9.Cu" signal "VCC1")
		(22 "In10.Cu" signal "GND4")
		(24 "In11.Cu" signal "IN4")
		(26 "In12.Cu" signal "GND5")
		(28 "In13.Cu" signal "IN5")
		(30 "In14.Cu" signal "GND6")
		(32 "In15.Cu" signal "IN6")
		(34 "In16.Cu" signal "GND7")
		(2 "B.Cu" signal "BOTTOM")
		(9 "F.Adhes" user "F.Adhesive")
		(11 "B.Adhes" user "B.Adhesive")
		(13 "F.Paste" user "Package Geometry/Pastemask Top")
		(15 "B.Paste" user "Package Geometry/Pastemask Bottom")
		(5 "F.SilkS" user "Ref Des/Silkscreen Top")
		(7 "B.SilkS" user "Ref Des/Silkscreen Bottom")
		(1 "F.Mask" user "Board Geometry/Soldermask Top")
		(3 "B.Mask" user "Board Geometry/Soldermask Bottom")
		(17 "Dwgs.User" user "User.Drawings")
		(19 "Cmts.User" user "User.Comments")
		(21 "Eco1.User" user "User.Eco1")
		(23 "Eco2.User" user "User.Eco2")
		(25 "Edge.Cuts" user "Board Geometry/Outline")
		(27 "Margin" user)
		(31 "F.CrtYd" user "Package Geometry/Place Bound Top")
		(29 "B.CrtYd" user "Package Geometry/Place Bound Bottom")
		(35 "F.Fab" user "Ref Des/Assembly Top")
		(33 "B.Fab" user "Ref Des/Assembly Bottom")
	)
	(footprint ""
		(layer "B.Cu")
		(at 358.389174 -400.19605 180)
		(property "Reference" "C625"
			(at 0 0 0)
			(layer "B.SilkS")
			(hide yes)
			(effects
				(font
					(size 1.27 1.27)
				)
				(justify mirror)
			)
		)
		(property "Value" ""
			(at 0 0 0)
			(layer "B.Fab")
			(effects
				(font
					(size 1.27 1.27)
				)
				(justify mirror)
			)
		)
		(duplicate_pad_numbers_are_jumpers no)
		(fp_line
			(start 1.524 0.762)
			(end 1.524 -0.762)
			(stroke
				(width 0.1524)
				(type default)
			)
			(layer "B.SilkS")
		)
		(fp_line
			(start 1.524 -0.762)
			(end -1.524 -0.762)
			(stroke
				(width 0.1524)
				(type default)
			)
			(layer "B.SilkS")
		)
		(fp_line
			(start -1.524 0.762)
			(end 1.524 0.762)
			(stroke
				(width 0.1524)
				(type default)
			)
			(layer "B.SilkS")
		)
		(fp_line
			(start -1.524 -0.762)
			(end -1.524 0.762)
			(stroke
				(width 0.1524)
				(type default)
			)
			(layer "B.SilkS")
		)
		(fp_line
			(start 1.1049 0.724916)
			(end -1.1049 0.724916)
			(stroke
				(width 0.1)
				(type default)
			)
			(layer "B.Fab")
		)
		(fp_line
			(start 1.1049 -0.724916)
			(end 1.1049 0.724916)
			(stroke
				(width 0.1)
				(type default)
			)
			(layer "B.Fab")
		)
		(fp_line
			(start -1.1049 0.724916)
			(end -1.1049 -0.724916)
			(stroke
				(width 0.1)
				(type default)
			)
			(layer "B.Fab")
		)
		(fp_line
			(start -1.1049 -0.724916)
			(end 1.1049 -0.724916)
			(stroke
				(width 0.1)
				(type default)
			)
			(layer "B.Fab")
		)
		(pad "1" smd rect
			(at 0.889 0 180)
			(size 1.016 1.27)
			(layers "B.Cu" "B.Mask" "B.Paste")
			(net "P0V9_CPU0_RT1_2A")
		)
		(pad "2" smd rect
			(at -0.889 0 180)
			(size 1.016 1.27)
			(layers "B.Cu" "B.Mask" "B.Paste")
			(net "GND")
		)
	)
	(footprint ""
		(layer "B.Cu")
		(at 415.569654 -170.48988 90)
		(property "Reference" "PC597"
			(at 5.924804 -1.286002 270)
			(unlocked yes)
			(layer "B.SilkS")
			(effects
				(font
					(size 0.7874 0.5842)
					(thickness 0.1524)
				)
				(justify left mirror)
			)
		)
		(property "Value" ""
			(at 0 0 90)
			(layer "B.Fab")
			(effects
				(font
					(size 1.27 1.27)
				)
				(justify mirror)
			)
		)
		(duplicate_pad_numbers_are_jumpers no)
		(fp_line
			(start 4.533392 -2.249932)
			(end -4.533392 -2.249932)
			(stroke
				(width 0.1524)
				(type default)
			)
			(layer "B.SilkS")
		)
		(fp_line
			(start -4.533392 -2.249932)
			(end -4.533392 2.249932)
			(stroke
				(width 0.1524)
				(type default)
			)
			(layer "B.SilkS")
		)
		(fp_line
			(start 4.533392 2.249932)
			(end 4.533392 -2.249932)
			(stroke
				(width 0.1524)
				(type default)
			)
			(layer "B.SilkS")
		)
		(fp_line
			(start -4.533392 2.249932)
			(end 4.533392 2.249932)
			(stroke
				(width 0.1524)
				(type default)
			)
			(layer "B.SilkS")
		)
		(fp_rect
			(start 4.533392 -2.326132)
			(end 5.39242 2.326132)
			(stroke
				(width 0)
				(type default)
			)
			(fill yes)
			(layer "B.SilkS")
		)
		(fp_line
			(start 3.750056 -2.249932)
			(end -3.750056 -2.249932)
			(stroke
				(width 0.1)
				(type default)
			)
			(layer "B.Fab")
		)
		(fp_line
			(start -3.750056 -2.249932)
			(end -3.750056 2.249932)
			(stroke
				(width 0.1)
				(type default)
			)
			(layer "B.Fab")
		)
		(fp_line
			(start 3.750056 2.249932)
			(end 3.750056 -2.249932)
			(stroke
				(width 0.1)
				(type default)
			)
			(layer "B.Fab")
		)
		(fp_line
			(start -3.750056 2.249932)
			(end 3.750056 2.249932)
			(stroke
				(width 0.1)
				(type default)
			)
			(layer "B.Fab")
		)
		(fp_text user "+"
			(at 6.322314 0.786384 0)
			(unlocked yes)
			(layer "B.SilkS")
			(effects
				(font
					(size 1.905 1.4224)
					(thickness 0.1524)
				)
				(justify left mirror)
			)
		)
		(fp_text user "-"
			(at -4.582668 1.44018 90)
			(unlocked yes)
			(layer "B.SilkS")
			(effects
				(font
					(size 1.905 1.4224)
					(thickness 0.1524)
				)
				(justify left mirror)
			)
		)
		(fp_text user "-"
			(at -4.8514 -0.14605 90)
			(unlocked yes)
			(layer "B.Fab")
			(effects
				(font
					(size 1.905 1.4224)
					(thickness 0.1524)
				)
				(justify left mirror)
			)
		)
		(fp_text user "+"
			(at 6.322314 0.786384 0)
			(unlocked yes)
			(layer "B.Fab")
			(effects
				(font
					(size 1.905 1.4224)
					(thickness 0.1524)
				)
				(justify left mirror)
			)
		)
		(pad "1" smd rect
			(at 3.199892 0 270)
			(size 2.413 2.8194)
			(layers "B.Cu" "B.Mask" "B.Paste")
			(net "PVDDCR_SOC_P0")
		)
		(pad "2" smd rect
			(at -3.199892 0 270)
			(size 2.413 2.8194)
			(layers "B.Cu" "B.Mask" "B.Paste")
			(net "GND")
		)
	)
	(footprint ""
		(layer "B.Cu")
		(at 378.878592 -395.148562 90)
		(property "Reference" "C1004"
			(at 0 0 90)
			(layer "B.SilkS")
			(hide yes)
			(effects
				(font
					(size 1.27 1.27)
				)
				(justify mirror)
			)
		)
		(property "Value" ""
			(at 0 0 90)
			(layer "B.Fab")
			(effects
				(font
					(size 1.27 1.27)
				)
				(justify mirror)
			)
		)
		(duplicate_pad_numbers_are_jumpers no)
		(fp_line
			(start 0.299974 -0.150114)
			(end -0.299974 -0.150114)
			(stroke
				(width 0.1)
				(type default)
			)
			(layer "B.Fab")
		)
		(fp_line
			(start -0.299974 -0.150114)
			(end -0.299974 0.150114)
			(stroke
				(width 0.1)
				(type default)
			)
			(layer "B.Fab")
		)
		(fp_line
			(start 0.299974 0.150114)
			(end 0.299974 -0.150114)
			(stroke
				(width 0.1)
				(type default)
			)
			(layer "B.Fab")
		)
		(fp_line
			(start -0.299974 0.150114)
			(end 0.299974 0.150114)
			(stroke
				(width 0.1)
				(type default)
			)
			(layer "B.Fab")
		)
		(pad "1" smd rect
			(at 0.2667 0 270)
			(size 0.3048 0.381)
			(layers "B.Cu" "B.Mask" "B.Paste")
			(net "P1V8_CPU0_RT3_1A")
		)
		(pad "2" smd rect
			(at -0.2667 0 270)
			(size 0.3048 0.381)
			(layers "B.Cu" "B.Mask" "B.Paste")
			(net "GND")
		)
	)
)
